# TIMECARD (Time Appliance Project (Time Card)) — schematic netlist excerpt (pin names and nets, part order shuffled) for the footprints in the layout excerpt that follows; sources: Cadence DE-HDL packaged netlist, KiCad conversion of R4006-B0001-02_R01.brd

C111  CAPACITOR  0.1UF 10V 10%  pkg SMC_0402R_H022  page 14 : \1\ = XP1R0V_FPGA_MGTAVCC ; \2\ = SG
C90  CAPACITOR  4.7UF 20%  pkg SMC_0402R_H026  page 24 : \1\ = FT4232_VREGOUT ; \2\ = SG

(kicad_pcb
	(version 20260206)
	(generator "pcbnew")
	(generator_version "10.0")
	(general
		(thickness 1.6)
		(legacy_teardrops no)
	)
	(paper "A4")
	(title_block
		(title "timecard-production-celestica-r4006 — R4006-B0001-02_R01.brd")
		(comment 1 "Time Appliance Project (Time Card) / footprints 839-840 of 1113")
	)
	(layers
		(0 "F.Cu" signal "TOP")
		(4 "In1.Cu" signal "L02_GND1")
		(6 "In2.Cu" signal "L03_SIG1")
		(8 "In3.Cu" signal "L04_GND2")
		(10 "In4.Cu" signal "L05_VCC1")
		(12 "In5.Cu" signal "L06_VCC2")
		(14 "In6.Cu" signal "L07_GND3")
		(16 "In7.Cu" signal "L08_SIG2")
		(18 "In8.Cu" signal "L09_GND4")
		(2 "B.Cu" signal "BOTTOM")
		(9 "F.Adhes" user "F.Adhesive")
		(11 "B.Adhes" user "B.Adhesive")
		(13 "F.Paste" user "Package Geometry/Pastemask Top")
		(15 "B.Paste" user "Package Geometry/Pastemask Bottom")
		(5 "F.SilkS" user "Ref Des/Silkscreen Top")
		(7 "B.SilkS" user "Ref Des/Silkscreen Bottom")
		(1 "F.Mask" user "Board Geometry/Soldermask Top")
		(3 "B.Mask" user "Board Geometry/Soldermask Bottom")
		(17 "Dwgs.User" user "User.Drawings")
		(19 "Cmts.User" user "User.Comments")
		(21 "Eco1.User" user "User.Eco1")
		(23 "Eco2.User" user "User.Eco2")
		(25 "Edge.Cuts" user "Board Geometry/Outline")
		(27 "Margin" user)
		(31 "F.CrtYd" user "Package Geometry/Place Bound Top")
		(29 "B.CrtYd" user "Package Geometry/Place Bound Bottom")
		(35 "F.Fab" user "Ref Des/Assembly Top")
		(33 "B.Fab" user "Ref Des/Assembly Bottom")
	)
	(footprint ""
		(layer "B.Cu")
		(at 26.289 -79.121 90)
		(property "Reference" "C90"
			(at 0 -1.18237 270)
			(unlocked yes)
			(layer "B.SilkS")
			(effects
				(font
					(size 0.7874 0.5842)
					(thickness 0.1524)
				)
				(justify mirror)
			)
		)
		(property "Value" "VAL*"
			(at -0.02032 2.13233 90)
			(unlocked yes)
			(layer "B.Fab")
			(hide yes)
			(effects
				(font
					(size 0.7874 0.5842)
					(thickness 0.1524)
				)
				(justify mirror)
			)
		)
		(property "Tolerance" "TOL*"
			(at -0.044704 3.05435 90)
			(unlocked yes)
			(layer "Cmts.User")
			(hide yes)
			(effects
				(font
					(size 0.7874 0.5842)
					(thickness 0.1524)
				)
				(justify mirror)
			)
		)
		(property "User Part Number" "PARTNUM*"
			(at -0.02032 4.024884 90)
			(unlocked yes)
			(layer "Cmts.User")
			(hide yes)
			(effects
				(font
					(size 0.7874 0.5842)
					(thickness 0.1524)
				)
				(justify mirror)
			)
		)
		(property "Device Type" "CAPACITOR-G105-0F475-BM,4.7UF,A"
			(at -0.008382 1.210564 90)
			(unlocked yes)
			(layer "B.Fab")
			(hide yes)
			(effects
				(font
					(size 0.7874 0.5842)
					(thickness 0.1524)
				)
				(justify mirror)
			)
		)
		(duplicate_pad_numbers_are_jumpers no)
		(fp_line
			(start 1.143 -0.5588)
			(end 1.143 0.5588)
			(stroke
				(width 0.1)
				(type default)
			)
			(layer "B.SilkS")
		)
		(fp_line
			(start -1.143 -0.5588)
			(end 1.143 -0.5588)
			(stroke
				(width 0.1)
				(type default)
			)
			(layer "B.SilkS")
		)
		(fp_line
			(start 1.143 0.5588)
			(end -1.143 0.5588)
			(stroke
				(width 0.1)
				(type default)
			)
			(layer "B.SilkS")
		)
		(fp_line
			(start -1.143 0.5588)
			(end -1.143 -0.5588)
			(stroke
				(width 0.1)
				(type default)
			)
			(layer "B.SilkS")
		)
		(fp_poly
			(pts
				(xy 1.143 0.5588) (xy -1.143 0.5588) (xy -1.143 -0.5588) (xy 1.143 -0.5588)
			)
			(stroke
				(width 0)
				(type default)
			)
			(fill no)
			(layer "B.CrtYd")
		)
		(fp_line
			(start 0.508 -0.3048)
			(end 0.508 0.3048)
			(stroke
				(width 0.1)
				(type default)
			)
			(layer "B.Fab")
		)
		(fp_line
			(start -0.508 -0.3048)
			(end 0.508 -0.3048)
			(stroke
				(width 0.1)
				(type default)
			)
			(layer "B.Fab")
		)
		(fp_line
			(start 0.508 0.3048)
			(end -0.508 0.3048)
			(stroke
				(width 0.1)
				(type default)
			)
			(layer "B.Fab")
		)
		(fp_line
			(start -0.508 0.3048)
			(end -0.508 -0.3048)
			(stroke
				(width 0.1)
				(type default)
			)
			(layer "B.Fab")
		)
		(pad "1" smd rect
			(at 0.5334 0 270)
			(size 0.7112 0.6096)
			(layers "B.Cu" "B.Mask" "B.Paste")
			(net "FT4232_VREGOUT")
		)
		(pad "2" smd rect
			(at -0.5334 0 270)
			(size 0.7112 0.6096)
			(layers "B.Cu" "B.Mask" "B.Paste")
			(net "SG")
		)
		(zone
			(layer "B.Cu")
			(hatch none 0.5)
			(connect_pads
				(clearance 0)
			)
			(min_thickness 0.25)
			(keepout
				(tracks allowed)
				(vias not_allowed)
				(pads allowed)
				(copperpour not_allowed)
				(footprints allowed)
			)
			(placement
				(enabled no)
				(sheetname "")
			)
			(fill
				(thermal_gap 0.5)
				(thermal_bridge_width 0.5)
				(island_removal_mode 0)
			)
			(polygon
				(pts
					(xy 26.5938 -79.1972) (xy 25.9842 -79.1972) (xy 25.9842 -79.0448) (xy 26.5938 -79.0448)
				)
			)
		)
		(zone
			(layer "B.Cu")
			(hatch none 0.5)
			(connect_pads
				(clearance 0)
			)
			(min_thickness 0.25)
			(keepout
				(tracks not_allowed)
				(vias allowed)
				(pads allowed)
				(copperpour not_allowed)
				(footprints allowed)
			)
			(placement
				(enabled no)
				(sheetname "")
			)
			(fill
				(thermal_gap 0.5)
				(thermal_bridge_width 0.5)
				(island_removal_mode 0)
			)
			(polygon
				(pts
					(xy 26.5938 -79.1972) (xy 25.9842 -79.1972) (xy 25.9842 -79.0448) (xy 26.5938 -79.0448)
				)
			)
		)
	)
	(footprint ""
		(layer "B.Cu")
		(at 104.347264 -40.823134 180)
		(property "Reference" "C111"
			(at 41.400984 -1.251204 0)
			(unlocked yes)
			(layer "B.SilkS")
			(effects
				(font
					(size 0.635 0.4064)
					(thickness 0.1524)
				)
				(justify mirror)
			)
		)
		(property "Value" "VAL*"
			(at 0 3.718306 180)
			(unlocked yes)
			(layer "B.Fab")
			(hide yes)
			(effects
				(font
					(size 0.7874 0.5842)
					(thickness 0.127)
				)
				(justify mirror)
			)
		)
		(property "Tolerance" "TOL*"
			(at 0 4.861306 180)
			(unlocked yes)
			(layer "Cmts.User")
			(hide yes)
			(effects
				(font
					(size 0.7874 0.5842)
					(thickness 0.127)
				)
				(justify mirror)
			)
		)
		(property "User Part Number" "PARTNUM*"
			(at 0 2.575306 180)
			(unlocked yes)
			(layer "Cmts.User")
			(hide yes)
			(effects
				(font
					(size 0.7874 0.5842)
					(thickness 0.127)
				)
				(justify mirror)
			)
		)
		(property "Device Type" "CAPACITOR-G105-0B104-CK,0.1UF,A"
			(at 0 1.432306 180)
			(unlocked yes)
			(layer "B.Fab")
			(hide yes)
			(effects
				(font
					(size 0.7874 0.5842)
					(thickness 0.127)
				)
				(justify mirror)
			)
		)
		(duplicate_pad_numbers_are_jumpers no)
		(fp_line
			(start 0.970026 0.4699)
			(end 0.970026 -0.4699)
			(stroke
				(width 0.1)
				(type default)
			)
			(layer "B.SilkS")
		)
		(fp_line
			(start 0.970026 -0.4699)
			(end -0.970026 -0.4699)
			(stroke
				(width 0.1)
				(type default)
			)
			(layer "B.SilkS")
		)
		(fp_line
			(start -0.970026 0.4699)
			(end 0.970026 0.4699)
			(stroke
				(width 0.1)
				(type default)
			)
			(layer "B.SilkS")
		)
		(fp_line
			(start -0.970026 -0.4699)
			(end -0.970026 0.4699)
			(stroke
				(width 0.1)
				(type default)
			)
			(layer "B.SilkS")
		)
		(fp_poly
			(pts
				(xy 0.970026 0.4699) (xy -0.970026 0.4699) (xy -0.970026 -0.4699) (xy 0.970026 -0.4699)
			)
			(stroke
				(width 0)
				(type default)
			)
			(fill no)
			(layer "B.CrtYd")
		)
		(fp_line
			(start 0.508 0.3048)
			(end 0.508 -0.3048)
			(stroke
				(width 0.1)
				(type default)
			)
			(layer "B.Fab")
		)
		(fp_line
			(start 0.508 -0.3048)
			(end -0.508 -0.3048)
			(stroke
				(width 0.1)
				(type default)
			)
			(layer "B.Fab")
		)
		(fp_line
			(start -0.508 0.3048)
			(end 0.508 0.3048)
			(stroke
				(width 0.1)
				(type default)
			)
			(layer "B.Fab")
		)
		(fp_line
			(start -0.508 -0.3048)
			(end -0.508 0.3048)
			(stroke
				(width 0.1)
				(type default)
			)
			(layer "B.Fab")
		)
		(pad "1" smd circle
			(at 0.500126 0)
			(size 0.635 0.635)
			(layers "B.Cu" "B.Mask" "B.Paste")
			(net "XP1R0V_FPGA_MGTAVCC")
		)
		(pad "2" smd circle
			(at -0.500126 0)
			(size 0.635 0.635)
			(layers "B.Cu" "B.Mask" "B.Paste")
			(net "SG")
		)
	)
)
